FILE_TYPE = MACRO_DRAWING;
SET COLOR_WIRE YELLOW;
SET COLOR_PROP ORANGE;
SET COLOR_DOT WHITE;
SET COLOR_ARC YELLOW;
SET COLOR_BODY GREEN;
SET COLOR_NOTE PURPLE;
SET PROP_DISPLAY VALUE;
SET PAGE_NUMBER P211;
FORCEADD QUANTA_TITLE_BLOCK_C..1
(0 0);
FORCEPROP 1 LAST CUSTOM_TXT_CDS <NAME_2>
J 0
(-3175 50);
FORCEPROP 1 LAST CUSTOM_TXT_CDS <NAME_1>
J 0
(-3175 175);
FORCEPROP 1 LAST CUSTOM_TXT_CDS <Q_NUMBER>
J 0
(-1403 103);
DISPLAY 1.212766 (-1403 103);
FORCEPROP 1 LAST CUSTOM_TXT_CDS <Q_PROJ>
J 0
(-2382 102);
DISPLAY 1.212766 (-2382 102);
FORCEPROP 1 LAST CUSTOM_TXT_CDS <Q_REV>
J 0
(-184 103);
DISPLAY 1.212766 (-184 103);
FORCEPROP 1 LAST CUSTOM_TXT_CDS <CON_LAST_MODIFIED>
J 0
(-1885 15);
DISPLAY 0.978723 (-1885 15);
FORCEPROP 1 LAST CUSTOM_TXT_CDS <CON_PAGE_NUM> OF <CON_TOTAL_PAGES>
J 0
(-446 18);
DISPLAY 0.978723 (-446 18);
FORCEPROP 1 LAST Q_TITLE DELTA-L
J 0
(-9366 26);
DISPLAY 2.446809 (-9366 26);
PAINT GREEN (-9366 26);
FORCEPROP 1 LAST Q_DEPT BU9
J 1
(-3763 49);
DISPLAY 1.957447 (-3763 49);
PAINT GREEN (-3763 49);
FORCEPROP 2 LAST PAGE_BORDER TRUE
J 0
(-7890 5250);
DISPLAY 0.638298 (-7890 5250);
PAINT PINK (-7890 5250);
DISPLAY INVISIBLE (-7890 5250);
FORCEPROP 1 LAST CDS_LMAN_SYM_OUTLINE -9475,6775,100,-125
J 0
(0 0);
DISPLAY 0.468085 (0 0);
PAINT GREEN (0 0);
DISPLAY INVISIBLE (0 0);
FORCEPROP 2 LAST CDS_LIB pure_quanta
J 0
(0 0);
DISPLAY INVISIBLE (0 0);
FORCEPROP 1 LAST COMMENT_BODY TRUE
J 0
(12 -13);
DISPLAY 0.978723 (12 -13);
PAINT GREEN (12 -13);
DISPLAY INVISIBLE (12 -13);
FORCEPROP 2 LAST CDS_XR_PAGE_TITLE CR-212 : @T6G_MB_LIB.T6G(SCH_1):PAGE212
J 0
(-7890 5250);
DISPLAY 0.638298 (-7890 5250);
PAINT PINK (-7890 5250);
DISPLAY INVISIBLE (-7890 5250);
FORCEPROP 2 LAST CUSTOM_TXT_CDS <XR_PAGE_TITLE>
J 0
(-7890 5250);
DISPLAY 0.638298 (-7890 5250);
PAINT PINK (-7890 5250);
DISPLAY INVISIBLE (-7890 5250);
FORCEPROP 0 LAST CDS_CON_LAST_MODIFIED Wed Mar 09 21:48:48 2022
J 0
(-1885 15);
DISPLAY INVISIBLE (-1885 15);
QUIT
